(kicad_pcb
	(version 20260206)
	(generator "pcbnew")
	(generator_version "10.0")
	(general
		(thickness 1.6)
		(legacy_teardrops no)
	)
	(paper "A4")
	(title_block
		(title "Wiwynn_Tioga_Pass_MB.brd")
		(comment 1 "Tioga Pass / footprints 549-555 of 4770")
	)
	(layers
		(0 "F.Cu" signal "TOP")
		(4 "In1.Cu" signal "L2GND")
		(6 "In2.Cu" signal "L3")
		(8 "In3.Cu" signal "L4GND")
		(10 "In4.Cu" signal "L5")
		(12 "In5.Cu" signal "L6GND")
		(14 "In6.Cu" signal "L7VCC")
		(16 "In7.Cu" signal "L8VCC")
		(18 "In8.Cu" signal "L9GND")
		(20 "In9.Cu" signal "L10")
		(22 "In10.Cu" signal "L11GND")
		(24 "In11.Cu" signal "L12")
		(26 "In12.Cu" signal "L13GND")
		(2 "B.Cu" signal "BOTTOM")
		(9 "F.Adhes" user "F.Adhesive")
		(11 "B.Adhes" user "B.Adhesive")
		(13 "F.Paste" user "Package Geometry/Pastemask Top")
		(15 "B.Paste" user "Package Geometry/Pastemask Bottom")
		(5 "F.SilkS" user "Ref Des/Silkscreen Top")
		(7 "B.SilkS" user "Ref Des/Silkscreen Bottom")
		(1 "F.Mask" user "Board Geometry/Soldermask Top")
		(3 "B.Mask" user "Board Geometry/Soldermask Bottom")
		(17 "Dwgs.User" user "User.Drawings")
		(19 "Cmts.User" user "User.Comments")
		(21 "Eco1.User" user "User.Eco1")
		(23 "Eco2.User" user "User.Eco2")
		(25 "Edge.Cuts" user "Board Geometry/Outline")
		(27 "Margin" user)
		(31 "F.CrtYd" user "Package Geometry/Place Bound Top")
		(29 "B.CrtYd" user "Package Geometry/Place Bound Bottom")
		(35 "F.Fab" user "Ref Des/Assembly Top")
		(33 "B.Fab" user "Ref Des/Assembly Bottom")
	)
	(footprint ""
		(layer "F.Cu")
		(at 108.252768 -79.6036 180)
		(property "Reference" "C3D4"
			(at 0 0 180)
			(layer "F.SilkS")
			(hide yes)
			(effects
				(font
					(size 1.27 1.27)
				)
			)
		)
		(property "Value" ""
			(at 0 0 180)
			(layer "F.Fab")
			(effects
				(font
					(size 1.27 1.27)
				)
			)
		)
		(duplicate_pad_numbers_are_jumpers no)
		(fp_poly
			(pts
				(xy -0.4953 -0.2032) (xy 0.4953 -0.2032) (xy 0.4953 1.6002) (xy -0.4953 1.6002)
			)
			(stroke
				(width 0)
				(type default)
			)
			(fill no)
			(layer "F.CrtYd")
		)
		(fp_line
			(start 0.4953 1.6002)
			(end -0.4953 1.6002)
			(stroke
				(width 0.1)
				(type default)
			)
			(layer "F.Fab")
		)
		(fp_line
			(start 0.4953 -0.2032)
			(end 0.4953 1.6002)
			(stroke
				(width 0.1)
				(type default)
			)
			(layer "F.Fab")
		)
		(fp_line
			(start -0.4953 1.6002)
			(end -0.4953 -0.2032)
			(stroke
				(width 0.1)
				(type default)
			)
			(layer "F.Fab")
		)
		(fp_line
			(start -0.4953 -0.2032)
			(end 0.4953 -0.2032)
			(stroke
				(width 0.1)
				(type default)
			)
			(layer "F.Fab")
		)
		(pad "1" smd rect
			(at 0 0 180)
			(size 0.762 0.889)
			(layers "F.Cu" "F.Mask" "F.Paste")
			(net "PVCCMCP_CPU1")
		)
		(pad "2" smd rect
			(at 0 1.397 180)
			(size 0.762 0.889)
			(layers "F.Cu" "F.Mask" "F.Paste")
			(net "GND")
		)
		(zone
			(layer "F.Cu")
			(hatch none 0.5)
			(connect_pads
				(clearance 0)
			)
			(min_thickness 0.25)
			(keepout
				(tracks not_allowed)
				(vias allowed)
				(pads allowed)
				(copperpour not_allowed)
				(footprints allowed)
			)
			(placement
				(enabled no)
				(sheetname "")
			)
			(fill
				(thermal_gap 0.5)
				(thermal_bridge_width 0.5)
				(island_removal_mode 0)
			)
			(polygon
				(pts
					(xy 108.633768 -80.0481) (xy 107.871768 -80.0481) (xy 107.871768 -80.5561) (xy 108.633768 -80.5561)
				)
			)
		)
	)
	(footprint ""
		(layer "F.Cu")
		(at 465.582 -22.225 -90)
		(property "Reference" "C8F2"
			(at 0 0 270)
			(layer "F.SilkS")
			(hide yes)
			(effects
				(font
					(size 1.27 1.27)
				)
			)
		)
		(property "Value" ""
			(at 0 0 270)
			(layer "F.Fab")
			(effects
				(font
					(size 1.27 1.27)
				)
			)
		)
		(duplicate_pad_numbers_are_jumpers no)
		(fp_rect
			(start 0.3048 0.9906)
			(end -0.3048 -0.1016)
			(stroke
				(width 0)
				(type default)
			)
			(fill no)
			(layer "F.CrtYd")
		)
		(fp_line
			(start -0.3048 0.9906)
			(end 0.3048 0.9906)
			(stroke
				(width 0.1)
				(type default)
			)
			(layer "F.Fab")
		)
		(fp_line
			(start 0.3048 0.9906)
			(end 0.3048 -0.1016)
			(stroke
				(width 0.1)
				(type default)
			)
			(layer "F.Fab")
		)
		(fp_line
			(start -0.3048 -0.1016)
			(end -0.3048 0.9906)
			(stroke
				(width 0.1)
				(type default)
			)
			(layer "F.Fab")
		)
		(fp_line
			(start 0.3048 -0.1016)
			(end -0.3048 -0.1016)
			(stroke
				(width 0.1)
				(type default)
			)
			(layer "F.Fab")
		)
		(pad "1" smd rect
			(at 0 0 270)
			(size 0.508 0.508)
			(layers "F.Cu" "F.Mask" "F.Paste")
			(net "PWRGD_P3V3_STBY_R")
		)
		(pad "2" smd rect
			(at 0 0.889 270)
			(size 0.508 0.508)
			(layers "F.Cu" "F.Mask" "F.Paste")
			(net "GND")
		)
		(zone
			(layer "F.Cu")
			(hatch none 0.5)
			(connect_pads
				(clearance 0)
			)
			(min_thickness 0.25)
			(keepout
				(tracks allowed)
				(vias not_allowed)
				(pads allowed)
				(copperpour not_allowed)
				(footprints allowed)
			)
			(placement
				(enabled no)
				(sheetname "")
			)
			(fill
				(thermal_gap 0.5)
				(thermal_bridge_width 0.5)
				(island_removal_mode 0)
			)
			(polygon
				(pts
					(xy 464.947 -21.971) (xy 465.328 -21.971) (xy 465.328 -22.479) (xy 464.947 -22.479)
				)
			)
		)
		(zone
			(layer "F.Cu")
			(hatch none 0.5)
			(connect_pads
				(clearance 0)
			)
			(min_thickness 0.25)
			(keepout
				(tracks not_allowed)
				(vias allowed)
				(pads allowed)
				(copperpour not_allowed)
				(footprints allowed)
			)
			(placement
				(enabled no)
				(sheetname "")
			)
			(fill
				(thermal_gap 0.5)
				(thermal_bridge_width 0.5)
				(island_removal_mode 0)
			)
			(polygon
				(pts
					(xy 464.947 -21.971) (xy 465.328 -21.971) (xy 465.328 -22.479) (xy 464.947 -22.479)
				)
			)
		)
	)
	(footprint ""
		(layer "F.Cu")
		(at 317.7286 -31.8516 90)
		(property "Reference" "C6F1"
			(at 0 0 90)
			(layer "F.SilkS")
			(hide yes)
			(effects
				(font
					(size 1.27 1.27)
				)
			)
		)
		(property "Value" ""
			(at 0 0 90)
			(layer "F.Fab")
			(effects
				(font
					(size 1.27 1.27)
				)
			)
		)
		(duplicate_pad_numbers_are_jumpers no)
		(fp_poly
			(pts
				(xy 0.3048 -0.1016) (xy 0.3048 0.9906) (xy -0.3048 0.9906) (xy -0.3048 -0.1016)
			)
			(stroke
				(width 0)
				(type default)
			)
			(fill no)
			(layer "F.CrtYd")
		)
		(fp_line
			(start 0.3048 -0.1016)
			(end -0.3048 -0.1016)
			(stroke
				(width 0.1)
				(type default)
			)
			(layer "F.Fab")
		)
		(fp_line
			(start -0.3048 -0.1016)
			(end -0.3048 0.9906)
			(stroke
				(width 0.1)
				(type default)
			)
			(layer "F.Fab")
		)
		(fp_line
			(start 0.3048 0.9906)
			(end 0.3048 -0.1016)
			(stroke
				(width 0.1)
				(type default)
			)
			(layer "F.Fab")
		)
		(fp_line
			(start -0.3048 0.9906)
			(end 0.3048 0.9906)
			(stroke
				(width 0.1)
				(type default)
			)
			(layer "F.Fab")
		)
		(pad "1" smd rect
			(at 0 0 90)
			(size 0.508 0.508)
			(layers "F.Cu" "F.Mask" "F.Paste")
			(net "P3V3")
		)
		(pad "2" smd rect
			(at 0 0.889 90)
			(size 0.508 0.508)
			(layers "F.Cu" "F.Mask" "F.Paste")
			(net "GND")
		)
		(zone
			(layer "F.Cu")
			(hatch none 0.5)
			(connect_pads
				(clearance 0)
			)
			(min_thickness 0.25)
			(keepout
				(tracks allowed)
				(vias not_allowed)
				(pads allowed)
				(copperpour not_allowed)
				(footprints allowed)
			)
			(placement
				(enabled no)
				(sheetname "")
			)
			(fill
				(thermal_gap 0.5)
				(thermal_bridge_width 0.5)
				(island_removal_mode 0)
			)
			(polygon
				(pts
					(xy 317.9826 -31.5976) (xy 317.9826 -32.1056) (xy 318.3636 -32.1056) (xy 318.3636 -31.5976)
				)
			)
		)
		(zone
			(layer "F.Cu")
			(hatch none 0.5)
			(connect_pads
				(clearance 0)
			)
			(min_thickness 0.25)
			(keepout
				(tracks not_allowed)
				(vias allowed)
				(pads allowed)
				(copperpour not_allowed)
				(footprints allowed)
			)
			(placement
				(enabled no)
				(sheetname "")
			)
			(fill
				(thermal_gap 0.5)
				(thermal_bridge_width 0.5)
				(island_removal_mode 0)
			)
			(polygon
				(pts
					(xy 318.3636 -31.5976) (xy 318.3636 -32.1056) (xy 317.9826 -32.1056) (xy 317.9826 -31.5976)
				)
			)
		)
	)
	(footprint ""
		(layer "F.Cu")
		(at 389.0645 -79.8322 -90)
		(property "Reference" "R7D32"
			(at 0 0 270)
			(layer "F.SilkS")
			(hide yes)
			(effects
				(font
					(size 1.27 1.27)
				)
			)
		)
		(property "Value" ""
			(at 0 0 270)
			(layer "F.Fab")
			(effects
				(font
					(size 1.27 1.27)
				)
			)
		)
		(duplicate_pad_numbers_are_jumpers no)
		(fp_poly
			(pts
				(xy -0.2794 -0.1016) (xy 0.2794 -0.1016) (xy 0.2794 0.9906) (xy -0.2794 0.9906)
			)
			(stroke
				(width 0)
				(type default)
			)
			(fill no)
			(layer "F.CrtYd")
		)
		(fp_line
			(start -0.2794 0.9906)
			(end 0.2794 0.9906)
			(stroke
				(width 0.1)
				(type default)
			)
			(layer "F.Fab")
		)
		(fp_line
			(start 0.2794 0.9906)
			(end 0.2794 -0.1016)
			(stroke
				(width 0.1)
				(type default)
			)
			(layer "F.Fab")
		)
		(fp_line
			(start -0.2794 -0.1016)
			(end -0.2794 0.9906)
			(stroke
				(width 0.1)
				(type default)
			)
			(layer "F.Fab")
		)
		(fp_line
			(start 0.2794 -0.1016)
			(end -0.2794 -0.1016)
			(stroke
				(width 0.1)
				(type default)
			)
			(layer "F.Fab")
		)
		(pad "1" smd rect
			(at 0 0 270)
			(size 0.508 0.508)
			(layers "F.Cu" "F.Mask" "F.Paste")
			(net "P0V7_GTL2104_VREF_0")
		)
		(pad "2" smd rect
			(at 0 0.889 270)
			(size 0.508 0.508)
			(layers "F.Cu" "F.Mask" "F.Paste")
			(net "GND")
		)
		(zone
			(layer "F.Cu")
			(hatch none 0.5)
			(connect_pads
				(clearance 0)
			)
			(min_thickness 0.25)
			(keepout
				(tracks not_allowed)
				(vias allowed)
				(pads allowed)
				(copperpour not_allowed)
				(footprints allowed)
			)
			(placement
				(enabled no)
				(sheetname "")
			)
			(fill
				(thermal_gap 0.5)
				(thermal_bridge_width 0.5)
				(island_removal_mode 0)
			)
			(polygon
				(pts
					(xy 388.4295 -80.0862) (xy 388.4295 -79.5782) (xy 388.8105 -79.5782) (xy 388.8105 -80.0862)
				)
			)
		)
		(zone
			(layer "F.Cu")
			(hatch none 0.5)
			(connect_pads
				(clearance 0)
			)
			(min_thickness 0.25)
			(keepout
				(tracks allowed)
				(vias not_allowed)
				(pads allowed)
				(copperpour not_allowed)
				(footprints allowed)
			)
			(placement
				(enabled no)
				(sheetname "")
			)
			(fill
				(thermal_gap 0.5)
				(thermal_bridge_width 0.5)
				(island_removal_mode 0)
			)
			(polygon
				(pts
					(xy 388.8105 -80.0862) (xy 388.8105 -79.5782) (xy 388.4295 -79.5782) (xy 388.4295 -80.0862)
				)
			)
		)
	)
	(footprint ""
		(layer "F.Cu")
		(at 447.301366 -28.33116 90)
		(property "Reference" "C25W6"
			(at -0.8382 -0.67818 90)
			(unlocked yes)
			(layer "F.SilkS")
			(effects
				(font
					(size 0.4064 0.254)
					(thickness 0.1524)
				)
				(justify left)
			)
		)
		(property "Value" ""
			(at 0 0 90)
			(layer "F.Fab")
			(effects
				(font
					(size 1.27 1.27)
				)
			)
		)
		(duplicate_pad_numbers_are_jumpers no)
		(fp_poly
			(pts
				(xy 0.3048 -0.1016) (xy 0.3048 0.9906) (xy -0.3048 0.9906) (xy -0.3048 -0.1016)
			)
			(stroke
				(width 0)
				(type default)
			)
			(fill no)
			(layer "F.CrtYd")
		)
		(fp_line
			(start 0.3048 -0.1016)
			(end -0.3048 -0.1016)
			(stroke
				(width 0.1)
				(type default)
			)
			(layer "F.Fab")
		)
		(fp_line
			(start -0.3048 -0.1016)
			(end -0.3048 0.9906)
			(stroke
				(width 0.1)
				(type default)
			)
			(layer "F.Fab")
		)
		(fp_line
			(start 0.3048 0.9906)
			(end 0.3048 -0.1016)
			(stroke
				(width 0.1)
				(type default)
			)
			(layer "F.Fab")
		)
		(fp_line
			(start -0.3048 0.9906)
			(end 0.3048 0.9906)
			(stroke
				(width 0.1)
				(type default)
			)
			(layer "F.Fab")
		)
		(pad "1" smd rect
			(at 0 0 90)
			(size 0.508 0.508)
			(layers "F.Cu" "F.Mask" "F.Paste")
			(net "P1V2_AUX_BMC")
		)
		(pad "2" smd rect
			(at 0 0.889 90)
			(size 0.508 0.508)
			(layers "F.Cu" "F.Mask" "F.Paste")
			(net "GND")
		)
		(zone
			(layer "F.Cu")
			(hatch none 0.5)
			(connect_pads
				(clearance 0)
			)
			(min_thickness 0.25)
			(keepout
				(tracks allowed)
				(vias not_allowed)
				(pads allowed)
				(copperpour not_allowed)
				(footprints allowed)
			)
			(placement
				(enabled no)
				(sheetname "")
			)
			(fill
				(thermal_gap 0.5)
				(thermal_bridge_width 0.5)
				(island_removal_mode 0)
			)
			(polygon
				(pts
					(xy 447.555366 -28.07716) (xy 447.555366 -28.58516) (xy 447.936366 -28.58516) (xy 447.936366 -28.07716)
				)
			)
		)
		(zone
			(layer "F.Cu")
			(hatch none 0.5)
			(connect_pads
				(clearance 0)
			)
			(min_thickness 0.25)
			(keepout
				(tracks not_allowed)
				(vias allowed)
				(pads allowed)
				(copperpour not_allowed)
				(footprints allowed)
			)
			(placement
				(enabled no)
				(sheetname "")
			)
			(fill
				(thermal_gap 0.5)
				(thermal_bridge_width 0.5)
				(island_removal_mode 0)
			)
			(polygon
				(pts
					(xy 447.936366 -28.07716) (xy 447.936366 -28.58516) (xy 447.555366 -28.58516) (xy 447.555366 -28.07716)
				)
			)
		)
	)
	(footprint ""
		(layer "F.Cu")
		(at 93.139768 -140.208 -90)
		(property "Reference" "C2A13"
			(at 1.848866 0.752348 270)
			(unlocked yes)
			(layer "F.SilkS")
			(effects
				(font
					(size 1.27 0.9652)
					(thickness 0.1524)
				)
			)
		)
		(property "Value" ""
			(at 0 0 270)
			(layer "F.Fab")
			(effects
				(font
					(size 1.27 1.27)
				)
			)
		)
		(duplicate_pad_numbers_are_jumpers no)
		(fp_rect
			(start -0.500126 1.598422)
			(end 0.500126 -0.201422)
			(stroke
				(width 0)
				(type default)
			)
			(fill no)
			(layer "F.CrtYd")
		)
		(fp_line
			(start -0.500126 1.598422)
			(end -0.500126 -0.201422)
			(stroke
				(width 0.1)
				(type default)
			)
			(layer "F.Fab")
		)
		(fp_line
			(start 0.500126 1.598422)
			(end -0.500126 1.598422)
			(stroke
				(width 0.1)
				(type default)
			)
			(layer "F.Fab")
		)
		(fp_line
			(start -0.500126 -0.201422)
			(end 0.500126 -0.201422)
			(stroke
				(width 0.1)
				(type default)
			)
			(layer "F.Fab")
		)
		(fp_line
			(start 0.500126 -0.201422)
			(end 0.500126 1.598422)
			(stroke
				(width 0.1)
				(type default)
			)
			(layer "F.Fab")
		)
		(pad "1" smd rect
			(at 0 0 180)
			(size 0.889 0.9906)
			(layers "F.Cu" "F.Mask" "F.Paste")
			(net "PVDDQ_KLM")
		)
		(pad "2" smd rect
			(at 0 1.397 180)
			(size 0.889 0.9906)
			(layers "F.Cu" "F.Mask" "F.Paste")
			(net "GND")
		)
		(zone
			(layer "F.Cu")
			(hatch none 0.5)
			(connect_pads
				(clearance 0)
			)
			(min_thickness 0.25)
			(keepout
				(tracks allowed)
				(vias not_allowed)
				(pads allowed)
				(copperpour not_allowed)
				(footprints allowed)
			)
			(placement
				(enabled no)
				(sheetname "")
			)
			(fill
				(thermal_gap 0.5)
				(thermal_bridge_width 0.5)
				(island_removal_mode 0)
			)
			(polygon
				(pts
					(xy 92.187268 -140.7033) (xy 92.187268 -139.7127) (xy 92.695268 -139.7127) (xy 92.695268 -140.7033)
				)
			)
		)
		(zone
			(layer "F.Cu")
			(hatch none 0.5)
			(connect_pads
				(clearance 0)
			)
			(min_thickness 0.25)
			(keepout
				(tracks not_allowed)
				(vias allowed)
				(pads allowed)
				(copperpour not_allowed)
				(footprints allowed)
			)
			(placement
				(enabled no)
				(sheetname "")
			)
			(fill
				(thermal_gap 0.5)
				(thermal_bridge_width 0.5)
				(island_removal_mode 0)
			)
			(polygon
				(pts
					(xy 92.187268 -140.7033) (xy 92.187268 -139.7127) (xy 92.695268 -139.7127) (xy 92.695268 -140.7033)
				)
			)
		)
	)
	(footprint ""
		(layer "F.Cu")
		(at 415.749994 -47.828962 180)
		(property "Reference" "R25W65"
			(at -0.8382 -0.67818 180)
			(unlocked yes)
			(layer "F.SilkS")
			(effects
				(font
					(size 0.4064 0.254)
					(thickness 0.1524)
				)
				(justify left)
			)
		)
		(property "Value" ""
			(at 0 0 180)
			(layer "F.Fab")
			(effects
				(font
					(size 1.27 1.27)
				)
			)
		)
		(duplicate_pad_numbers_are_jumpers no)
		(fp_poly
			(pts
				(xy -0.2794 -0.1016) (xy 0.2794 -0.1016) (xy 0.2794 0.9906) (xy -0.2794 0.9906)
			)
			(stroke
				(width 0)
				(type default)
			)
			(fill no)
			(layer "F.CrtYd")
		)
		(fp_line
			(start 0.2794 0.9906)
			(end 0.2794 -0.1016)
			(stroke
				(width 0.1)
				(type default)
			)
			(layer "F.Fab")
		)
		(fp_line
			(start 0.2794 -0.1016)
			(end -0.2794 -0.1016)
			(stroke
				(width 0.1)
				(type default)
			)
			(layer "F.Fab")
		)
		(fp_line
			(start -0.2794 0.9906)
			(end 0.2794 0.9906)
			(stroke
				(width 0.1)
				(type default)
			)
			(layer "F.Fab")
		)
		(fp_line
			(start -0.2794 -0.1016)
			(end -0.2794 0.9906)
			(stroke
				(width 0.1)
				(type default)
			)
			(layer "F.Fab")
		)
		(pad "1" smd rect
			(at 0 0 180)
			(size 0.508 0.508)
			(layers "F.Cu" "F.Mask" "F.Paste")
			(net "P2E_SSB_BMC_TX_C_DN")
		)
		(pad "2" smd rect
			(at 0 0.889 180)
			(size 0.508 0.508)
			(layers "F.Cu" "F.Mask" "F.Paste")
			(net "GND")
		)
		(zone
			(layer "F.Cu")
			(hatch none 0.5)
			(connect_pads
				(clearance 0)
			)
			(min_thickness 0.25)
			(keepout
				(tracks not_allowed)
				(vias allowed)
				(pads allowed)
				(copperpour not_allowed)
				(footprints allowed)
			)
			(placement
				(enabled no)
				(sheetname "")
			)
			(fill
				(thermal_gap 0.5)
				(thermal_bridge_width 0.5)
				(island_removal_mode 0)
			)
			(polygon
				(pts
					(xy 416.003994 -48.463962) (xy 415.495994 -48.463962) (xy 415.495994 -48.082962) (xy 416.003994 -48.082962)
				)
			)
		)
		(zone
			(layer "F.Cu")
			(hatch none 0.5)
			(connect_pads
				(clearance 0)
			)
			(min_thickness 0.25)
			(keepout
				(tracks allowed)
				(vias not_allowed)
				(pads allowed)
				(copperpour not_allowed)
				(footprints allowed)
			)
			(placement
				(enabled no)
				(sheetname "")
			)
			(fill
				(thermal_gap 0.5)
				(thermal_bridge_width 0.5)
				(island_removal_mode 0)
			)
			(polygon
				(pts
					(xy 416.003994 -48.082962) (xy 415.495994 -48.082962) (xy 415.495994 -48.463962) (xy 416.003994 -48.463962)
				)
			)
		)
	)
)
